(kicad_pcb
	(version 20260206)
	(generator "pcbnew")
	(generator_version "10.0")
	(general
		(thickness 1.6)
		(legacy_teardrops no)
	)
	(paper "A4")
	(title_block
		(title "01162023_DA0F0TEBIF0_F0T_Expander_BD_F_brd_V02_OCP.brd")
		(comment 1 "Grand Teton / footprints 255-261 of 9728")
	)
	(layers
		(0 "F.Cu" signal "TOP")
		(4 "In1.Cu" signal "GND")
		(6 "In2.Cu" signal "VCC")
		(8 "In3.Cu" signal "VCC1")
		(10 "In4.Cu" signal "GND1")
		(12 "In5.Cu" signal "IN1")
		(14 "In6.Cu" signal "GND2")
		(16 "In7.Cu" signal "IN2")
		(18 "In8.Cu" signal "GND3")
		(20 "In9.Cu" signal "IN3")
		(22 "In10.Cu" signal "GND4")
		(24 "In11.Cu" signal "IN4")
		(26 "In12.Cu" signal "GND5")
		(28 "In13.Cu" signal "IN5")
		(30 "In14.Cu" signal "GND6")
		(32 "In15.Cu" signal "IN6")
		(34 "In16.Cu" signal "GND7")
		(2 "B.Cu" signal "BOTTOM")
		(9 "F.Adhes" user "F.Adhesive")
		(11 "B.Adhes" user "B.Adhesive")
		(13 "F.Paste" user "Package Geometry/Pastemask Top")
		(15 "B.Paste" user "Package Geometry/Pastemask Bottom")
		(5 "F.SilkS" user "Ref Des/Silkscreen Top")
		(7 "B.SilkS" user "Ref Des/Silkscreen Bottom")
		(1 "F.Mask" user "Board Geometry/Soldermask Top")
		(3 "B.Mask" user "Board Geometry/Soldermask Bottom")
		(17 "Dwgs.User" user "User.Drawings")
		(19 "Cmts.User" user "User.Comments")
		(21 "Eco1.User" user "User.Eco1")
		(23 "Eco2.User" user "User.Eco2")
		(25 "Edge.Cuts" user "Board Geometry/Outline")
		(27 "Margin" user)
		(31 "F.CrtYd" user "Package Geometry/Place Bound Top")
		(29 "B.CrtYd" user "Package Geometry/Place Bound Bottom")
		(35 "F.Fab" user "Ref Des/Assembly Top")
		(33 "B.Fab" user "Ref Des/Assembly Bottom")
	)
	(footprint ""
		(layer "F.Cu")
		(at 136.445244 -98.100642 180)
		(property "Reference" "R1574"
			(at 0 0 180)
			(layer "F.SilkS")
			(hide yes)
			(effects
				(font
					(size 1.27 1.27)
				)
			)
		)
		(property "Value" ""
			(at 0 0 180)
			(layer "F.Fab")
			(effects
				(font
					(size 1.27 1.27)
				)
			)
		)
		(duplicate_pad_numbers_are_jumpers no)
		(fp_line
			(start 0.7874 0.4064)
			(end -0.7874 0.4064)
			(stroke
				(width 0.1524)
				(type default)
			)
			(layer "F.SilkS")
		)
		(fp_line
			(start 0.7874 -0.4064)
			(end 0.7874 0.4064)
			(stroke
				(width 0.1524)
				(type default)
			)
			(layer "F.SilkS")
		)
		(fp_line
			(start -0.7874 0.4064)
			(end -0.7874 -0.4064)
			(stroke
				(width 0.1524)
				(type default)
			)
			(layer "F.SilkS")
		)
		(fp_line
			(start -0.7874 -0.4064)
			(end 0.7874 -0.4064)
			(stroke
				(width 0.1524)
				(type default)
			)
			(layer "F.SilkS")
		)
		(fp_line
			(start 0.67945 0.3048)
			(end 0.120396 0.3048)
			(stroke
				(width 0.1)
				(type default)
			)
			(layer "F.Fab")
		)
		(fp_line
			(start 0.67945 -0.3048)
			(end 0.67945 0.3048)
			(stroke
				(width 0.1)
				(type default)
			)
			(layer "F.Fab")
		)
		(fp_line
			(start 0.12065 -0.2794)
			(end 0.12065 -0.3048)
			(stroke
				(width 0.1)
				(type default)
			)
			(layer "F.Fab")
		)
		(fp_line
			(start 0.12065 -0.3048)
			(end 0.67945 -0.3048)
			(stroke
				(width 0.1)
				(type default)
			)
			(layer "F.Fab")
		)
		(fp_line
			(start 0.120396 0.3048)
			(end 0.120396 0.2794)
			(stroke
				(width 0.1)
				(type default)
			)
			(layer "F.Fab")
		)
		(fp_line
			(start 0.120396 0.2794)
			(end -0.12065 0.2794)
			(stroke
				(width 0.1)
				(type default)
			)
			(layer "F.Fab")
		)
		(fp_line
			(start -0.12065 0.3048)
			(end -0.67945 0.3048)
			(stroke
				(width 0.1)
				(type default)
			)
			(layer "F.Fab")
		)
		(fp_line
			(start -0.12065 0.2794)
			(end -0.12065 0.3048)
			(stroke
				(width 0.1)
				(type default)
			)
			(layer "F.Fab")
		)
		(fp_line
			(start -0.12065 -0.2794)
			(end 0.12065 -0.2794)
			(stroke
				(width 0.1)
				(type default)
			)
			(layer "F.Fab")
		)
		(fp_line
			(start -0.12065 -0.305054)
			(end -0.12065 -0.2794)
			(stroke
				(width 0.1)
				(type default)
			)
			(layer "F.Fab")
		)
		(fp_line
			(start -0.67945 0.3048)
			(end -0.67945 -0.305054)
			(stroke
				(width 0.1)
				(type default)
			)
			(layer "F.Fab")
		)
		(fp_line
			(start -0.67945 -0.305054)
			(end -0.12065 -0.305054)
			(stroke
				(width 0.1)
				(type default)
			)
			(layer "F.Fab")
		)
		(pad "1" smd circle
			(at -0.40005 0 180)
			(size 0 0)
			(layers "F.Cu" "F.Mask" "F.Paste")
			(net "SMB_BIC_I2C9_SSD_MUX_R_SCL")
		)
		(pad "2" smd circle
			(at 0.40005 0 180)
			(size 0 0)
			(layers "F.Cu" "F.Mask" "F.Paste")
			(net "SMB_BIC_I2C9_SSD_MUX0_SCL")
		)
	)
	(footprint ""
		(layer "F.Cu")
		(at 31.754318 -48.21809)
		(property "Reference" "PD62"
			(at -3.306318 2.24536 0)
			(unlocked yes)
			(layer "F.SilkS")
			(effects
				(font
					(size 0.7874 0.5842)
					(thickness 0.1524)
				)
				(justify left)
			)
		)
		(property "Value" ""
			(at 0 0 0)
			(layer "F.Fab")
			(effects
				(font
					(size 1.27 1.27)
				)
			)
		)
		(duplicate_pad_numbers_are_jumpers no)
		(fp_line
			(start -3.400044 -1.459992)
			(end 4.107942 -1.459992)
			(stroke
				(width 0.1524)
				(type default)
			)
			(layer "F.SilkS")
		)
		(fp_line
			(start -3.400044 1.459992)
			(end -3.400044 -1.459992)
			(stroke
				(width 0.1524)
				(type default)
			)
			(layer "F.SilkS")
		)
		(fp_line
			(start 4.107942 -1.459992)
			(end 4.107942 1.459992)
			(stroke
				(width 0.1524)
				(type default)
			)
			(layer "F.SilkS")
		)
		(fp_line
			(start 4.107942 1.459992)
			(end -3.400044 1.459992)
			(stroke
				(width 0.1524)
				(type default)
			)
			(layer "F.SilkS")
		)
		(fp_poly
			(pts
				(xy 4.107942 -1.459992) (xy 4.107942 1.459992) (xy 3.308096 1.459992) (xy 3.308096 -1.459992)
			)
			(stroke
				(width 0)
				(type default)
			)
			(fill yes)
			(layer "F.SilkS")
		)
		(fp_line
			(start -2.29997 -1.459992)
			(end 2.29997 -1.459992)
			(stroke
				(width 0.1)
				(type default)
			)
			(layer "F.Fab")
		)
		(fp_line
			(start -2.29997 1.459992)
			(end -2.29997 -1.459992)
			(stroke
				(width 0.1)
				(type default)
			)
			(layer "F.Fab")
		)
		(fp_line
			(start 2.29997 -1.459992)
			(end 2.29997 1.459992)
			(stroke
				(width 0.1)
				(type default)
			)
			(layer "F.Fab")
		)
		(fp_line
			(start 2.29997 1.459992)
			(end -2.29997 1.459992)
			(stroke
				(width 0.1)
				(type default)
			)
			(layer "F.Fab")
		)
		(fp_text user "+"
			(at -4.7752 -0.12065 0)
			(unlocked yes)
			(layer "F.SilkS")
			(effects
				(font
					(size 1.905 1.4224)
					(thickness 0.1524)
				)
				(justify left)
			)
		)
		(fp_text user "-"
			(at 5.4102 0.29845 180)
			(unlocked yes)
			(layer "F.SilkS")
			(effects
				(font
					(size 1.905 1.4224)
					(thickness 0.1524)
				)
				(justify left)
			)
		)
		(fp_text user "+"
			(at -4.7752 -0.12065 0)
			(unlocked yes)
			(layer "F.Fab")
			(effects
				(font
					(size 1.905 1.4224)
					(thickness 0.1524)
				)
				(justify left)
			)
		)
		(fp_text user "-"
			(at 5.4102 0.29845 180)
			(unlocked yes)
			(layer "F.Fab")
			(effects
				(font
					(size 1.905 1.4224)
					(thickness 0.1524)
				)
				(justify left)
			)
		)
		(pad "A" smd rect
			(at -1.999996 0 90)
			(size 1.7018 2.5146)
			(layers "F.Cu" "F.Mask" "F.Paste")
			(net "GND")
		)
		(pad "C" smd rect
			(at 1.999996 0 90)
			(size 1.7018 2.5146)
			(layers "F.Cu" "F.Mask" "F.Paste")
			(net "P3V3_SSD1")
		)
	)
	(footprint ""
		(layer "F.Cu")
		(at 162.160712 -350.098614 90)
		(property "Reference" "C2512"
			(at 0 0 90)
			(layer "F.SilkS")
			(hide yes)
			(effects
				(font
					(size 1.27 1.27)
				)
			)
		)
		(property "Value" ""
			(at 0 0 90)
			(layer "F.Fab")
			(effects
				(font
					(size 1.27 1.27)
				)
			)
		)
		(duplicate_pad_numbers_are_jumpers no)
		(fp_line
			(start 0.299974 -0.150114)
			(end 0.299974 0.150114)
			(stroke
				(width 0.1)
				(type default)
			)
			(layer "F.Fab")
		)
		(fp_line
			(start -0.299974 -0.150114)
			(end 0.299974 -0.150114)
			(stroke
				(width 0.1)
				(type default)
			)
			(layer "F.Fab")
		)
		(fp_line
			(start 0.299974 0.150114)
			(end -0.299974 0.150114)
			(stroke
				(width 0.1)
				(type default)
			)
			(layer "F.Fab")
		)
		(fp_line
			(start -0.299974 0.150114)
			(end -0.299974 -0.150114)
			(stroke
				(width 0.1)
				(type default)
			)
			(layer "F.Fab")
		)
		(pad "1" smd rect
			(at -0.2667 0 90)
			(size 0.3048 0.381)
			(layers "F.Cu" "F.Mask" "F.Paste")
			(net "P5E_PEX1_STN4_TX_DP<79>")
		)
		(pad "2" smd rect
			(at 0.2667 0 90)
			(size 0.3048 0.381)
			(layers "F.Cu" "F.Mask" "F.Paste")
			(net "P5E_PEX1_STN4_TX_C_DP<79>")
		)
	)
	(footprint ""
		(layer "F.Cu")
		(at 172.947838 -40.037258 90)
		(property "Reference" "U369"
			(at 0.399542 2.313432 90)
			(unlocked yes)
			(layer "F.SilkS")
			(effects
				(font
					(size 0.7874 0.5842)
					(thickness 0.1524)
				)
			)
		)
		(property "Value" ""
			(at 0 0 90)
			(layer "F.Fab")
			(effects
				(font
					(size 1.27 1.27)
				)
			)
		)
		(duplicate_pad_numbers_are_jumpers no)
		(fp_line
			(start -1.949958 -1.610106)
			(end 1.949958 -1.610106)
			(stroke
				(width 0.1524)
				(type default)
			)
			(layer "F.SilkS")
		)
		(fp_line
			(start 1.949958 -1.560068)
			(end 1.949958 1.610106)
			(stroke
				(width 0.1524)
				(type default)
			)
			(layer "F.SilkS")
		)
		(fp_line
			(start 1.949958 1.610106)
			(end -1.949958 1.610106)
			(stroke
				(width 0.1524)
				(type default)
			)
			(layer "F.SilkS")
		)
		(fp_line
			(start -1.949958 1.610106)
			(end -1.949958 -1.610106)
			(stroke
				(width 0.1524)
				(type default)
			)
			(layer "F.SilkS")
		)
		(fp_line
			(start 0.750062 -1.560068)
			(end 0.750062 1.560068)
			(stroke
				(width 0.1)
				(type default)
			)
			(layer "F.Fab")
		)
		(fp_line
			(start -0.750062 -1.560068)
			(end 0.750062 -1.560068)
			(stroke
				(width 0.1)
				(type default)
			)
			(layer "F.Fab")
		)
		(fp_line
			(start 0.750062 1.560068)
			(end -0.750062 1.560068)
			(stroke
				(width 0.1)
				(type default)
			)
			(layer "F.Fab")
		)
		(fp_line
			(start -0.750062 1.560068)
			(end -0.750062 -1.560068)
			(stroke
				(width 0.1)
				(type default)
			)
			(layer "F.Fab")
		)
		(pad "D" smd rect
			(at 1.100074 0)
			(size 1.016 1.4224)
			(layers "F.Cu" "F.Mask" "F.Paste")
			(net "SSD6_AUX_P3V3_EN")
		)
		(pad "G" smd rect
			(at -1.100074 -0.94996)
			(size 1.016 1.4224)
			(layers "F.Cu" "F.Mask" "F.Paste")
			(net "PRSNT_SSD6_R1_N")
		)
		(pad "S" smd rect
			(at -1.100074 0.94996)
			(size 1.016 1.4224)
			(layers "F.Cu" "F.Mask" "F.Paste")
			(net "GND")
		)
	)
	(footprint ""
		(layer "F.Cu")
		(at 386.899912 -151.279352 180)
		(property "Reference" "R322"
			(at 0 0 180)
			(layer "F.SilkS")
			(hide yes)
			(effects
				(font
					(size 1.27 1.27)
				)
			)
		)
		(property "Value" ""
			(at 0 0 180)
			(layer "F.Fab")
			(effects
				(font
					(size 1.27 1.27)
				)
			)
		)
		(duplicate_pad_numbers_are_jumpers no)
		(fp_line
			(start 0.7874 0.4064)
			(end -0.7874 0.4064)
			(stroke
				(width 0.1524)
				(type default)
			)
			(layer "F.SilkS")
		)
		(fp_line
			(start 0.7874 -0.4064)
			(end 0.7874 0.4064)
			(stroke
				(width 0.1524)
				(type default)
			)
			(layer "F.SilkS")
		)
		(fp_line
			(start -0.7874 0.4064)
			(end -0.7874 -0.4064)
			(stroke
				(width 0.1524)
				(type default)
			)
			(layer "F.SilkS")
		)
		(fp_line
			(start -0.7874 -0.4064)
			(end 0.7874 -0.4064)
			(stroke
				(width 0.1524)
				(type default)
			)
			(layer "F.SilkS")
		)
		(fp_line
			(start 0.67945 0.3048)
			(end 0.120396 0.3048)
			(stroke
				(width 0.1)
				(type default)
			)
			(layer "F.Fab")
		)
		(fp_line
			(start 0.67945 -0.3048)
			(end 0.67945 0.3048)
			(stroke
				(width 0.1)
				(type default)
			)
			(layer "F.Fab")
		)
		(fp_line
			(start 0.12065 -0.2794)
			(end 0.12065 -0.3048)
			(stroke
				(width 0.1)
				(type default)
			)
			(layer "F.Fab")
		)
		(fp_line
			(start 0.12065 -0.3048)
			(end 0.67945 -0.3048)
			(stroke
				(width 0.1)
				(type default)
			)
			(layer "F.Fab")
		)
		(fp_line
			(start 0.120396 0.3048)
			(end 0.120396 0.2794)
			(stroke
				(width 0.1)
				(type default)
			)
			(layer "F.Fab")
		)
		(fp_line
			(start 0.120396 0.2794)
			(end -0.12065 0.2794)
			(stroke
				(width 0.1)
				(type default)
			)
			(layer "F.Fab")
		)
		(fp_line
			(start -0.12065 0.3048)
			(end -0.67945 0.3048)
			(stroke
				(width 0.1)
				(type default)
			)
			(layer "F.Fab")
		)
		(fp_line
			(start -0.12065 0.2794)
			(end -0.12065 0.3048)
			(stroke
				(width 0.1)
				(type default)
			)
			(layer "F.Fab")
		)
		(fp_line
			(start -0.12065 -0.2794)
			(end 0.12065 -0.2794)
			(stroke
				(width 0.1)
				(type default)
			)
			(layer "F.Fab")
		)
		(fp_line
			(start -0.12065 -0.305054)
			(end -0.12065 -0.2794)
			(stroke
				(width 0.1)
				(type default)
			)
			(layer "F.Fab")
		)
		(fp_line
			(start -0.67945 0.3048)
			(end -0.67945 -0.305054)
			(stroke
				(width 0.1)
				(type default)
			)
			(layer "F.Fab")
		)
		(fp_line
			(start -0.67945 -0.305054)
			(end -0.12065 -0.305054)
			(stroke
				(width 0.1)
				(type default)
			)
			(layer "F.Fab")
		)
		(pad "1" smd circle
			(at -0.40005 0 180)
			(size 0 0)
			(layers "F.Cu" "F.Mask" "F.Paste")
			(net "NCSI_NIC6_RXD0")
		)
		(pad "2" smd circle
			(at 0.40005 0 180)
			(size 0 0)
			(layers "F.Cu" "F.Mask" "F.Paste")
			(net "GND")
		)
	)
	(footprint ""
		(layer "F.Cu")
		(at 145.697956 -198.2978)
		(property "Reference" "R6642"
			(at 0 0 0)
			(layer "F.SilkS")
			(hide yes)
			(effects
				(font
					(size 1.27 1.27)
				)
			)
		)
		(property "Value" ""
			(at 0 0 0)
			(layer "F.Fab")
			(effects
				(font
					(size 1.27 1.27)
				)
			)
		)
		(duplicate_pad_numbers_are_jumpers no)
		(fp_line
			(start -0.7874 -0.4064)
			(end 0.7874 -0.4064)
			(stroke
				(width 0.1524)
				(type default)
			)
			(layer "F.SilkS")
		)
		(fp_line
			(start -0.7874 0.4064)
			(end -0.7874 -0.4064)
			(stroke
				(width 0.1524)
				(type default)
			)
			(layer "F.SilkS")
		)
		(fp_line
			(start 0.7874 -0.4064)
			(end 0.7874 0.4064)
			(stroke
				(width 0.1524)
				(type default)
			)
			(layer "F.SilkS")
		)
		(fp_line
			(start 0.7874 0.4064)
			(end -0.7874 0.4064)
			(stroke
				(width 0.1524)
				(type default)
			)
			(layer "F.SilkS")
		)
		(fp_line
			(start -0.67945 -0.305054)
			(end -0.12065 -0.305054)
			(stroke
				(width 0.1)
				(type default)
			)
			(layer "F.Fab")
		)
		(fp_line
			(start -0.67945 0.3048)
			(end -0.67945 -0.305054)
			(stroke
				(width 0.1)
				(type default)
			)
			(layer "F.Fab")
		)
		(fp_line
			(start -0.12065 -0.305054)
			(end -0.12065 -0.2794)
			(stroke
				(width 0.1)
				(type default)
			)
			(layer "F.Fab")
		)
		(fp_line
			(start -0.12065 -0.2794)
			(end 0.12065 -0.2794)
			(stroke
				(width 0.1)
				(type default)
			)
			(layer "F.Fab")
		)
		(fp_line
			(start -0.12065 0.2794)
			(end -0.12065 0.3048)
			(stroke
				(width 0.1)
				(type default)
			)
			(layer "F.Fab")
		)
		(fp_line
			(start -0.12065 0.3048)
			(end -0.67945 0.3048)
			(stroke
				(width 0.1)
				(type default)
			)
			(layer "F.Fab")
		)
		(fp_line
			(start 0.120396 0.2794)
			(end -0.12065 0.2794)
			(stroke
				(width 0.1)
				(type default)
			)
			(layer "F.Fab")
		)
		(fp_line
			(start 0.120396 0.3048)
			(end 0.120396 0.2794)
			(stroke
				(width 0.1)
				(type default)
			)
			(layer "F.Fab")
		)
		(fp_line
			(start 0.12065 -0.3048)
			(end 0.67945 -0.3048)
			(stroke
				(width 0.1)
				(type default)
			)
			(layer "F.Fab")
		)
		(fp_line
			(start 0.12065 -0.2794)
			(end 0.12065 -0.3048)
			(stroke
				(width 0.1)
				(type default)
			)
			(layer "F.Fab")
		)
		(fp_line
			(start 0.67945 -0.3048)
			(end 0.67945 0.3048)
			(stroke
				(width 0.1)
				(type default)
			)
			(layer "F.Fab")
		)
		(fp_line
			(start 0.67945 0.3048)
			(end 0.120396 0.3048)
			(stroke
				(width 0.1)
				(type default)
			)
			(layer "F.Fab")
		)
		(pad "1" smd circle
			(at -0.40005 0)
			(size 0 0)
			(layers "F.Cu" "F.Mask" "F.Paste")
			(net "UART_PEX1_CLI_RX")
		)
		(pad "2" smd circle
			(at 0.40005 0)
			(size 0 0)
			(layers "F.Cu" "F.Mask" "F.Paste")
			(net "UART_PEX1_CLI_R_RX")
		)
	)
	(footprint ""
		(layer "F.Cu")
		(at 205.578964 -308.323488 135)
		(property "Reference" "R1321"
			(at 0 0 135)
			(layer "F.SilkS")
			(hide yes)
			(effects
				(font
					(size 1.27 1.27)
				)
			)
		)
		(property "Value" ""
			(at 0 0 135)
			(layer "F.Fab")
			(effects
				(font
					(size 1.27 1.27)
				)
			)
		)
		(duplicate_pad_numbers_are_jumpers no)
		(fp_line
			(start 0.787389 -0.406267)
			(end 0.787389 0.406267)
			(stroke
				(width 0.1524)
				(type default)
			)
			(layer "F.SilkS")
		)
		(fp_line
			(start 0.787389 0.406267)
			(end -0.787389 0.406267)
			(stroke
				(width 0.1524)
				(type default)
			)
			(layer "F.SilkS")
		)
		(fp_line
			(start -0.787389 -0.406267)
			(end 0.787389 -0.406267)
			(stroke
				(width 0.1524)
				(type default)
			)
			(layer "F.SilkS")
		)
		(fp_line
			(start -0.787389 0.406267)
			(end -0.787389 -0.406267)
			(stroke
				(width 0.1524)
				(type default)
			)
			(layer "F.SilkS")
		)
		(fp_line
			(start 0.679446 -0.30479)
			(end 0.679446 0.30479)
			(stroke
				(width 0.1)
				(type default)
			)
			(layer "F.Fab")
		)
		(fp_line
			(start 0.120515 -0.30479)
			(end 0.679446 -0.30479)
			(stroke
				(width 0.1)
				(type default)
			)
			(layer "F.Fab")
		)
		(fp_line
			(start 0.120695 -0.279466)
			(end 0.120515 -0.30479)
			(stroke
				(width 0.1)
				(type default)
			)
			(layer "F.Fab")
		)
		(fp_line
			(start 0.679446 0.30479)
			(end 0.120515 0.30479)
			(stroke
				(width 0.1)
				(type default)
			)
			(layer "F.Fab")
		)
		(fp_line
			(start -0.120695 -0.304969)
			(end -0.120695 -0.279466)
			(stroke
				(width 0.1)
				(type default)
			)
			(layer "F.Fab")
		)
		(fp_line
			(start -0.120695 -0.279466)
			(end 0.120695 -0.279466)
			(stroke
				(width 0.1)
				(type default)
			)
			(layer "F.Fab")
		)
		(fp_line
			(start 0.120335 0.279466)
			(end -0.120695 0.279466)
			(stroke
				(width 0.1)
				(type default)
			)
			(layer "F.Fab")
		)
		(fp_line
			(start 0.120515 0.30479)
			(end 0.120335 0.279466)
			(stroke
				(width 0.1)
				(type default)
			)
			(layer "F.Fab")
		)
		(fp_line
			(start -0.679446 -0.305149)
			(end -0.120695 -0.304969)
			(stroke
				(width 0.1)
				(type default)
			)
			(layer "F.Fab")
		)
		(fp_line
			(start -0.120695 0.279466)
			(end -0.120515 0.30479)
			(stroke
				(width 0.1)
				(type default)
			)
			(layer "F.Fab")
		)
		(fp_line
			(start -0.120515 0.30479)
			(end -0.679446 0.30479)
			(stroke
				(width 0.1)
				(type default)
			)
			(layer "F.Fab")
		)
		(fp_line
			(start -0.679446 0.30479)
			(end -0.679446 -0.305149)
			(stroke
				(width 0.1)
				(type default)
			)
			(layer "F.Fab")
		)
		(pad "1" smd circle
			(at -0.40005 0 135)
			(size 0 0)
			(layers "F.Cu" "F.Mask" "F.Paste")
			(net "GND")
		)
		(pad "2" smd circle
			(at 0.40005 0 135)
			(size 0 0)
			(layers "F.Cu" "F.Mask" "F.Paste")
			(net "PEX1_SPARE7")
		)
	)
)
